# SCM (Grand Teton) — schematic netlist excerpt (pin names and nets, part order shuffled) for the footprints in the layout excerpt that follows; sources: Cadence DE-HDL packaged netlist, KiCad conversion of 12092022_DA0F0TMDCD0_F0T_Management_Board_D_brd_V3_OCP.brd

R865  Q_RES  1K 1% EMPTY  pkg 0402LF  page 14 : A = FM_BOARD_BMC_REV_ID0 ; B = GND
C49  Q_CAP  0.1UF 25V 10% X7R  pkg 0402  page 17 : A = P1V8_STBY_AVDDPLL ; B = GND
C265  Q_CAP  22UF 16V 20% X6S  pkg C0805  page 52 : A = SW_P3V3_AUX_FLT ; B = GND

(kicad_pcb
	(version 20260206)
	(generator "pcbnew")
	(generator_version "10.0")
	(general
		(thickness 1.6)
		(legacy_teardrops no)
	)
	(paper "A4")
	(title_block
		(title "12092022_DA0F0TMDCD0_F0T_Management_Board_D_brd_V3_OCP.brd")
		(comment 1 "Grand Teton / footprints 832-834 of 1440")
	)
	(layers
		(0 "F.Cu" signal "TOP")
		(4 "In1.Cu" signal "GND")
		(6 "In2.Cu" signal "IN1")
		(8 "In3.Cu" signal "GND1")
		(10 "In4.Cu" signal "IN2")
		(12 "In5.Cu" signal "VCC")
		(14 "In6.Cu" signal "VCC1")
		(16 "In7.Cu" signal "IN3")
		(18 "In8.Cu" signal "GND2")
		(20 "In9.Cu" signal "IN4")
		(22 "In10.Cu" signal "GND3")
		(2 "B.Cu" signal "BOTTOM")
		(9 "F.Adhes" user "F.Adhesive")
		(11 "B.Adhes" user "B.Adhesive")
		(13 "F.Paste" user "Package Geometry/Pastemask Top")
		(15 "B.Paste" user "Package Geometry/Pastemask Bottom")
		(5 "F.SilkS" user "Ref Des/Silkscreen Top")
		(7 "B.SilkS" user "Ref Des/Silkscreen Bottom")
		(1 "F.Mask" user "Board Geometry/Soldermask Top")
		(3 "B.Mask" user "Board Geometry/Soldermask Bottom")
		(17 "Dwgs.User" user "User.Drawings")
		(19 "Cmts.User" user "User.Comments")
		(21 "Eco1.User" user "User.Eco1")
		(23 "Eco2.User" user "User.Eco2")
		(25 "Edge.Cuts" user "Board Geometry/Outline")
		(27 "Margin" user)
		(31 "F.CrtYd" user "Package Geometry/Place Bound Top")
		(29 "B.CrtYd" user "Package Geometry/Place Bound Bottom")
		(35 "F.Fab" user "Ref Des/Assembly Top")
		(33 "B.Fab" user "Ref Des/Assembly Bottom")
	)
	(footprint ""
		(layer "B.Cu")
		(at 70.358 -19.685 90)
		(property "Reference" "R865"
			(at 0 0 90)
			(layer "B.SilkS")
			(hide yes)
			(effects
				(font
					(size 1.27 1.27)
				)
				(justify mirror)
			)
		)
		(property "Value" ""
			(at 0 0 90)
			(layer "B.Fab")
			(effects
				(font
					(size 1.27 1.27)
				)
				(justify mirror)
			)
		)
		(duplicate_pad_numbers_are_jumpers no)
		(fp_line
			(start 0.7874 -0.4064)
			(end -0.7874 -0.4064)
			(stroke
				(width 0.1524)
				(type default)
			)
			(layer "B.SilkS")
		)
		(fp_line
			(start -0.7874 -0.4064)
			(end -0.7874 0.4064)
			(stroke
				(width 0.1524)
				(type default)
			)
			(layer "B.SilkS")
		)
		(fp_line
			(start 0.7874 0.4064)
			(end 0.7874 -0.4064)
			(stroke
				(width 0.1524)
				(type default)
			)
			(layer "B.SilkS")
		)
		(fp_line
			(start -0.7874 0.4064)
			(end 0.7874 0.4064)
			(stroke
				(width 0.1524)
				(type default)
			)
			(layer "B.SilkS")
		)
		(fp_line
			(start 0.67945 -0.305054)
			(end 0.12065 -0.305054)
			(stroke
				(width 0.1)
				(type default)
			)
			(layer "B.Fab")
		)
		(fp_line
			(start 0.12065 -0.305054)
			(end 0.12065 -0.2794)
			(stroke
				(width 0.1)
				(type default)
			)
			(layer "B.Fab")
		)
		(fp_line
			(start -0.12065 -0.3048)
			(end -0.67945 -0.3048)
			(stroke
				(width 0.1)
				(type default)
			)
			(layer "B.Fab")
		)
		(fp_line
			(start -0.67945 -0.3048)
			(end -0.67945 0.3048)
			(stroke
				(width 0.1)
				(type default)
			)
			(layer "B.Fab")
		)
		(fp_line
			(start 0.12065 -0.2794)
			(end -0.12065 -0.2794)
			(stroke
				(width 0.1)
				(type default)
			)
			(layer "B.Fab")
		)
		(fp_line
			(start -0.12065 -0.2794)
			(end -0.12065 -0.3048)
			(stroke
				(width 0.1)
				(type default)
			)
			(layer "B.Fab")
		)
		(fp_line
			(start 0.12065 0.2794)
			(end 0.12065 0.3048)
			(stroke
				(width 0.1)
				(type default)
			)
			(layer "B.Fab")
		)
		(fp_line
			(start -0.120396 0.2794)
			(end 0.12065 0.2794)
			(stroke
				(width 0.1)
				(type default)
			)
			(layer "B.Fab")
		)
		(fp_line
			(start 0.67945 0.3048)
			(end 0.67945 -0.305054)
			(stroke
				(width 0.1)
				(type default)
			)
			(layer "B.Fab")
		)
		(fp_line
			(start 0.12065 0.3048)
			(end 0.67945 0.3048)
			(stroke
				(width 0.1)
				(type default)
			)
			(layer "B.Fab")
		)
		(fp_line
			(start -0.120396 0.3048)
			(end -0.120396 0.2794)
			(stroke
				(width 0.1)
				(type default)
			)
			(layer "B.Fab")
		)
		(fp_line
			(start -0.67945 0.3048)
			(end -0.120396 0.3048)
			(stroke
				(width 0.1)
				(type default)
			)
			(layer "B.Fab")
		)
		(pad "1" smd circle
			(at 0.40005 0 270)
			(size 0 0)
			(layers "B.Cu" "B.Mask" "B.Paste")
			(net "FM_BOARD_BMC_REV_ID0")
		)
		(pad "2" smd circle
			(at -0.40005 0 270)
			(size 0 0)
			(layers "B.Cu" "B.Mask" "B.Paste")
			(net "GND")
		)
	)
	(footprint ""
		(layer "B.Cu")
		(at 61.330586 -49.314354)
		(property "Reference" "C49"
			(at 0 0 0)
			(layer "B.SilkS")
			(hide yes)
			(effects
				(font
					(size 1.27 1.27)
				)
				(justify mirror)
			)
		)
		(property "Value" ""
			(at 0 0 0)
			(layer "B.Fab")
			(effects
				(font
					(size 1.27 1.27)
				)
				(justify mirror)
			)
		)
		(duplicate_pad_numbers_are_jumpers no)
		(fp_line
			(start -0.7874 -0.4064)
			(end -0.7874 0.4064)
			(stroke
				(width 0.1524)
				(type default)
			)
			(layer "B.SilkS")
		)
		(fp_line
			(start -0.7874 0.4064)
			(end 0.7874 0.4064)
			(stroke
				(width 0.1524)
				(type default)
			)
			(layer "B.SilkS")
		)
		(fp_line
			(start 0.7874 -0.4064)
			(end -0.7874 -0.4064)
			(stroke
				(width 0.1524)
				(type default)
			)
			(layer "B.SilkS")
		)
		(fp_line
			(start 0.7874 0.4064)
			(end 0.7874 -0.4064)
			(stroke
				(width 0.1524)
				(type default)
			)
			(layer "B.SilkS")
		)
		(fp_line
			(start -0.67945 -0.3048)
			(end -0.67945 0.3048)
			(stroke
				(width 0.1)
				(type default)
			)
			(layer "B.Fab")
		)
		(fp_line
			(start -0.67945 0.3048)
			(end -0.120396 0.3048)
			(stroke
				(width 0.1)
				(type default)
			)
			(layer "B.Fab")
		)
		(fp_line
			(start -0.12065 -0.3048)
			(end -0.67945 -0.3048)
			(stroke
				(width 0.1)
				(type default)
			)
			(layer "B.Fab")
		)
		(fp_line
			(start -0.12065 -0.2794)
			(end -0.12065 -0.3048)
			(stroke
				(width 0.1)
				(type default)
			)
			(layer "B.Fab")
		)
		(fp_line
			(start -0.120396 0.2794)
			(end 0.12065 0.2794)
			(stroke
				(width 0.1)
				(type default)
			)
			(layer "B.Fab")
		)
		(fp_line
			(start -0.120396 0.3048)
			(end -0.120396 0.2794)
			(stroke
				(width 0.1)
				(type default)
			)
			(layer "B.Fab")
		)
		(fp_line
			(start 0.12065 -0.305054)
			(end 0.12065 -0.2794)
			(stroke
				(width 0.1)
				(type default)
			)
			(layer "B.Fab")
		)
		(fp_line
			(start 0.12065 -0.2794)
			(end -0.12065 -0.2794)
			(stroke
				(width 0.1)
				(type default)
			)
			(layer "B.Fab")
		)
		(fp_line
			(start 0.12065 0.2794)
			(end 0.12065 0.3048)
			(stroke
				(width 0.1)
				(type default)
			)
			(layer "B.Fab")
		)
		(fp_line
			(start 0.12065 0.3048)
			(end 0.67945 0.3048)
			(stroke
				(width 0.1)
				(type default)
			)
			(layer "B.Fab")
		)
		(fp_line
			(start 0.67945 -0.305054)
			(end 0.12065 -0.305054)
			(stroke
				(width 0.1)
				(type default)
			)
			(layer "B.Fab")
		)
		(fp_line
			(start 0.67945 0.3048)
			(end 0.67945 -0.305054)
			(stroke
				(width 0.1)
				(type default)
			)
			(layer "B.Fab")
		)
		(pad "1" smd circle
			(at 0.40005 0 180)
			(size 0 0)
			(layers "B.Cu" "B.Mask" "B.Paste")
			(net "P1V8_STBY_AVDDPLL")
		)
		(pad "2" smd circle
			(at -0.40005 0 180)
			(size 0 0)
			(layers "B.Cu" "B.Mask" "B.Paste")
			(net "GND")
		)
	)
	(footprint ""
		(layer "B.Cu")
		(at 7.239 -61.087)
		(property "Reference" "C265"
			(at 0 0 0)
			(layer "B.SilkS")
			(hide yes)
			(effects
				(font
					(size 1.27 1.27)
				)
				(justify mirror)
			)
		)
		(property "Value" ""
			(at 0 0 0)
			(layer "B.Fab")
			(effects
				(font
					(size 1.27 1.27)
				)
				(justify mirror)
			)
		)
		(duplicate_pad_numbers_are_jumpers no)
		(fp_line
			(start -1.524 -0.762)
			(end -1.524 0.762)
			(stroke
				(width 0.1524)
				(type default)
			)
			(layer "B.SilkS")
		)
		(fp_line
			(start -1.524 0.762)
			(end 1.524 0.762)
			(stroke
				(width 0.1524)
				(type default)
			)
			(layer "B.SilkS")
		)
		(fp_line
			(start 1.524 -0.762)
			(end -1.524 -0.762)
			(stroke
				(width 0.1524)
				(type default)
			)
			(layer "B.SilkS")
		)
		(fp_line
			(start 1.524 0.762)
			(end 1.524 -0.762)
			(stroke
				(width 0.1524)
				(type default)
			)
			(layer "B.SilkS")
		)
		(fp_line
			(start -1.1049 -0.724916)
			(end 1.1049 -0.724916)
			(stroke
				(width 0.1)
				(type default)
			)
			(layer "B.Fab")
		)
		(fp_line
			(start -1.1049 0.724916)
			(end -1.1049 -0.724916)
			(stroke
				(width 0.1)
				(type default)
			)
			(layer "B.Fab")
		)
		(fp_line
			(start 1.1049 -0.724916)
			(end 1.1049 0.724916)
			(stroke
				(width 0.1)
				(type default)
			)
			(layer "B.Fab")
		)
		(fp_line
			(start 1.1049 0.724916)
			(end -1.1049 0.724916)
			(stroke
				(width 0.1)
				(type default)
			)
			(layer "B.Fab")
		)
		(pad "1" smd rect
			(at 0.889 0)
			(size 1.016 1.27)
			(layers "B.Cu" "B.Mask" "B.Paste")
			(net "SW_P3V3_AUX_FLT")
		)
		(pad "2" smd rect
			(at -0.889 0)
			(size 1.016 1.27)
			(layers "B.Cu" "B.Mask" "B.Paste")
			(net "GND")
		)
	)
)
